(kicad_pcb
	(version 20260206)
	(generator "pcbnew")
	(generator_version "10.0")
	(general
		(thickness 1.6)
		(legacy_teardrops no)
	)
	(paper "A4")
	(title_block
		(title "peb — Lightning_PEB_BRD.brd")
		(comment 1 "Lightning (Wiwynn / Facebook NVMe JBOF) / footprints 393-399 of 2563")
	)
	(layers
		(0 "F.Cu" signal "TOP")
		(4 "In1.Cu" signal "L2GND")
		(6 "In2.Cu" signal "L3")
		(8 "In3.Cu" signal "L4VCC")
		(10 "In4.Cu" signal "L5VCC")
		(12 "In5.Cu" signal "L6")
		(14 "In6.Cu" signal "L7GND")
		(2 "B.Cu" signal "BOTTOM")
		(9 "F.Adhes" user "F.Adhesive")
		(11 "B.Adhes" user "B.Adhesive")
		(13 "F.Paste" user "Package Geometry/Pastemask Top")
		(15 "B.Paste" user "Package Geometry/Pastemask Bottom")
		(5 "F.SilkS" user "Ref Des/Silkscreen Top")
		(7 "B.SilkS" user "Ref Des/Silkscreen Bottom")
		(1 "F.Mask" user "Board Geometry/Soldermask Top")
		(3 "B.Mask" user "Board Geometry/Soldermask Bottom")
		(17 "Dwgs.User" user "User.Drawings")
		(19 "Cmts.User" user "User.Comments")
		(21 "Eco1.User" user "User.Eco1")
		(23 "Eco2.User" user "User.Eco2")
		(25 "Edge.Cuts" user "Board Geometry/Outline")
		(27 "Margin" user)
		(31 "F.CrtYd" user "Package Geometry/Place Bound Top")
		(29 "B.CrtYd" user "Package Geometry/Place Bound Bottom")
		(35 "F.Fab" user "Ref Des/Assembly Top")
		(33 "B.Fab" user "Ref Des/Assembly Bottom")
	)
	(footprint ""
		(layer "F.Cu")
		(at 264.07745 -4.340098 180)
		(property "Reference" "C266"
			(at 0 0 180)
			(layer "F.SilkS")
			(hide yes)
			(effects
				(font
					(size 1.27 1.27)
				)
			)
		)
		(property "Value" "SCD1U16V2JX-1-GP"
			(at 1.1811 -2.7051 180)
			(unlocked yes)
			(layer "F.Fab")
			(hide yes)
			(effects
				(font
					(size 1.016 1.016)
					(thickness 0.1524)
				)
			)
		)
		(property "Device Type" "C402H22"
			(at 1.1811 -4.2291 180)
			(unlocked yes)
			(layer "F.Fab")
			(hide yes)
			(effects
				(font
					(size 1.016 1.016)
					(thickness 0.1524)
				)
			)
		)
		(duplicate_pad_numbers_are_jumpers no)
		(fp_rect
			(start -0.4318 0.9525)
			(end 0.4318 -0.9525)
			(stroke
				(width 0)
				(type default)
			)
			(fill no)
			(layer "F.CrtYd")
		)
		(fp_rect
			(start -0.4318 0.9525)
			(end 0.4318 -0.9525)
			(stroke
				(width 0)
				(type default)
			)
			(fill no)
			(layer "F.Fab")
		)
		(pad "1" smd custom
			(at 0 -0.4445 180)
			(size 0.1524 0.1524)
			(layers "F.Cu" "F.Mask" "F.Paste")
			(net "RST_BTN#")
			(options
				(clearance outline)
				(anchor circle)
			)
			(primitives
				(gr_poly
					(pts
						(arc
							(start 0.3048 -0.2032)
							(mid 0.275042 -0.275042)
							(end 0.2032 -0.3048)
						)
						(arc
							(start -0.2032 -0.3048)
							(mid -0.275042 -0.275042)
							(end -0.3048 -0.2032)
						)
						(arc
							(start -0.3048 0.2032)
							(mid -0.275042 0.275042)
							(end -0.2032 0.3048)
						)
						(arc
							(start 0.2032 0.3048)
							(mid 0.275042 0.275042)
							(end 0.3048 0.2032)
						)
					)
					(width 0)
					(fill yes)
				)
			)
		)
		(pad "2" smd custom
			(at 0 0.4445 180)
			(size 0.1524 0.1524)
			(layers "F.Cu" "F.Mask" "F.Paste")
			(net "GND")
			(options
				(clearance outline)
				(anchor circle)
			)
			(primitives
				(gr_poly
					(pts
						(arc
							(start 0.3048 -0.2032)
							(mid 0.275042 -0.275042)
							(end 0.2032 -0.3048)
						)
						(arc
							(start -0.2032 -0.3048)
							(mid -0.275042 -0.275042)
							(end -0.3048 -0.2032)
						)
						(arc
							(start -0.3048 0.2032)
							(mid -0.275042 0.275042)
							(end -0.2032 0.3048)
						)
						(arc
							(start 0.2032 0.3048)
							(mid 0.275042 0.275042)
							(end 0.3048 0.2032)
						)
					)
					(width 0)
					(fill yes)
				)
			)
		)
	)
	(footprint ""
		(layer "F.Cu")
		(at 273.100038 -25.940004 90)
		(property "Reference" "CN9"
			(at 0 0 90)
			(layer "F.SilkS")
			(hide yes)
			(effects
				(font
					(size 1.27 1.27)
				)
			)
		)
		(property "Value" "FOX-CON2-S23-GP"
			(at 5.334 1.4478 90)
			(unlocked yes)
			(layer "F.Fab")
			(hide yes)
			(effects
				(font
					(size 1.016 1.016)
					(thickness 0.1524)
				)
			)
		)
		(property "Device Type" "HBA1030-H300R-EF"
			(at 5.334 -0.0762 90)
			(unlocked yes)
			(layer "F.Fab")
			(hide yes)
			(effects
				(font
					(size 1.016 1.016)
					(thickness 0.1524)
				)
			)
		)
		(duplicate_pad_numbers_are_jumpers no)
		(fp_line
			(start -4.082288 -1.63576)
			(end -2.812288 -1.63576)
			(stroke
				(width 0.4064)
				(type default)
			)
			(layer "F.SilkS")
		)
		(fp_line
			(start 3.937 -1.4859)
			(end 3.937 1.4859)
			(stroke
				(width 0.1524)
				(type default)
			)
			(layer "F.SilkS")
		)
		(fp_line
			(start -3.937 -1.4859)
			(end 3.937 -1.4859)
			(stroke
				(width 0.1524)
				(type default)
			)
			(layer "F.SilkS")
		)
		(fp_line
			(start -4.082288 -0.36576)
			(end -4.082288 -1.63576)
			(stroke
				(width 0.4064)
				(type default)
			)
			(layer "F.SilkS")
		)
		(fp_line
			(start 3.937 1.4859)
			(end -3.937 1.4859)
			(stroke
				(width 0.1524)
				(type default)
			)
			(layer "F.SilkS")
		)
		(fp_line
			(start -3.937 1.4859)
			(end -3.937 -1.4859)
			(stroke
				(width 0.1524)
				(type default)
			)
			(layer "F.SilkS")
		)
		(fp_circle
			(center 2.54 0)
			(end 2.54 1.0668)
			(stroke
				(width 0.3048)
				(type default)
			)
			(fill no)
			(layer "F.SilkS")
		)
		(fp_circle
			(center -2.54 0)
			(end -2.54 1.0668)
			(stroke
				(width 0.3048)
				(type default)
			)
			(fill no)
			(layer "F.SilkS")
		)
		(fp_rect
			(start -3.683 1.2319)
			(end 3.683 -1.2319)
			(stroke
				(width 0)
				(type default)
			)
			(fill no)
			(layer "F.CrtYd")
		)
		(fp_poly
			(pts
				(xy -4.191 1.7399) (xy -4.191 -1.7399) (xy 4.191 -1.7399) (xy 4.191 1.7399) (xy -0.2413 1.7399)
				(xy -0.2413 1.2319) (xy 3.683 1.2319) (xy 3.683 -1.2319) (xy -3.683 -1.2319) (xy -3.683 1.2319)
				(xy -0.254 1.2319) (xy -0.254 1.7399)
			)
			(stroke
				(width 0)
				(type default)
			)
			(fill no)
			(layer "F.CrtYd")
		)
		(fp_rect
			(start -4.191 1.7399)
			(end 4.191 -1.7399)
			(stroke
				(width 0)
				(type default)
			)
			(fill no)
			(layer "F.Fab")
		)
		(pad "1" thru_hole circle
			(at -2.54 0 90)
			(size 1.4224 1.4224)
			(drill 1.016)
			(layers "*.Cu" "*.Mask")
			(remove_unused_layers no)
			(net "GND")
			(clearance 0.1524)
			(thermal_gap 0.1524)
		)
		(pad "2" thru_hole circle
			(at 2.54 0 90)
			(size 1.4224 1.4224)
			(drill 1.016)
			(layers "*.Cu" "*.Mask")
			(remove_unused_layers no)
			(net "GND")
			(clearance 0.1524)
			(thermal_gap 0.1524)
		)
	)
	(footprint ""
		(layer "F.Cu")
		(at 10.287 -120.65 180)
		(property "Reference" "U8"
			(at 0 0 180)
			(layer "F.SilkS")
			(hide yes)
			(effects
				(font
					(size 1.27 1.27)
				)
			)
		)
		(property "Value" "2N7002DW-7F-GP"
			(at -2.3622 -8.2042 180)
			(unlocked yes)
			(layer "F.Fab")
			(hide yes)
			(effects
				(font
					(size 1.016 1.016)
					(thickness 0.1524)
				)
			)
		)
		(property "Device Type" "SOT-363H44"
			(at -2.3622 -10.1092 180)
			(unlocked yes)
			(layer "F.Fab")
			(hide yes)
			(effects
				(font
					(size 1.016 1.016)
					(thickness 0.1524)
				)
			)
		)
		(duplicate_pad_numbers_are_jumpers no)
		(fp_line
			(start 1.4478 1.7018)
			(end 1.4478 -1.7018)
			(stroke
				(width 0.1524)
				(type default)
			)
			(layer "F.SilkS")
		)
		(fp_line
			(start 1.4478 -1.7018)
			(end -1.4478 -1.7018)
			(stroke
				(width 0.1524)
				(type default)
			)
			(layer "F.SilkS")
		)
		(fp_line
			(start -1.27 1.524)
			(end -1.27 0.6604)
			(stroke
				(width 0.4826)
				(type default)
			)
			(layer "F.SilkS")
		)
		(fp_line
			(start -1.4478 1.7018)
			(end 1.4478 1.7018)
			(stroke
				(width 0.1524)
				(type default)
			)
			(layer "F.SilkS")
		)
		(fp_line
			(start -1.4478 -1.7018)
			(end -1.4478 1.7018)
			(stroke
				(width 0.1524)
				(type default)
			)
			(layer "F.SilkS")
		)
		(fp_poly
			(pts
				(xy -1.524 -1.778) (xy 1.524 -1.778) (xy 1.524 1.778) (xy -1.524 1.778)
			)
			(stroke
				(width 0)
				(type default)
			)
			(fill no)
			(layer "F.CrtYd")
		)
		(fp_poly
			(pts
				(xy -1.524 -1.778) (xy 1.524 -1.778) (xy 1.524 1.778) (xy -1.524 1.778)
			)
			(stroke
				(width 0)
				(type default)
			)
			(fill no)
			(layer "F.Fab")
		)
		(pad "1" smd rect
			(at -0.65024 0.9398 180)
			(size 0.4064 1.016)
			(layers "F.Cu" "F.Mask" "F.Paste")
			(net "BMC_I2C1_MINI1_SCL_S")
		)
		(pad "2" smd rect
			(at 0 0.9398 180)
			(size 0.4064 1.016)
			(layers "F.Cu" "F.Mask" "F.Paste")
			(net "I2C1_LS_G2")
		)
		(pad "3" smd rect
			(at 0.65024 0.9398 180)
			(size 0.4064 1.016)
			(layers "F.Cu" "F.Mask" "F.Paste")
			(net "BMC_I2C1_MINI1_SDA")
		)
		(pad "4" smd rect
			(at 0.65024 -0.9398 180)
			(size 0.4064 1.016)
			(layers "F.Cu" "F.Mask" "F.Paste")
			(net "BMC_I2C1_MINI1_SDA_S")
		)
		(pad "5" smd rect
			(at 0 -0.9398 180)
			(size 0.4064 1.016)
			(layers "F.Cu" "F.Mask" "F.Paste")
			(net "I2C1_LS_G1")
		)
		(pad "6" smd rect
			(at -0.65024 -0.9398 180)
			(size 0.4064 1.016)
			(layers "F.Cu" "F.Mask" "F.Paste")
			(net "BMC_I2C1_MINI1_SCL")
		)
	)
	(footprint ""
		(layer "F.Cu")
		(at 22.4663 -178.3461 -90)
		(property "Reference" "R690"
			(at 0 0 270)
			(layer "F.SilkS")
			(hide yes)
			(effects
				(font
					(size 1.27 1.27)
				)
			)
		)
		(property "Value" "10KR3F-L-GP"
			(at -0.0254 -2.5146 270)
			(unlocked yes)
			(layer "F.Fab")
			(hide yes)
			(effects
				(font
					(size 1.016 1.016)
					(thickness 0.1524)
				)
			)
		)
		(property "Device Type" "R603H22"
			(at -0.0254 -4.0386 270)
			(unlocked yes)
			(layer "F.Fab")
			(hide yes)
			(effects
				(font
					(size 1.016 1.016)
					(thickness 0.1524)
				)
			)
		)
		(duplicate_pad_numbers_are_jumpers no)
		(fp_line
			(start -0.4826 0)
			(end -0.2032 0)
			(stroke
				(width 0.2032)
				(type default)
			)
			(layer "F.SilkS")
		)
		(fp_line
			(start 0.2032 0)
			(end 0.4826 0)
			(stroke
				(width 0.2032)
				(type default)
			)
			(layer "F.SilkS")
		)
		(fp_rect
			(start -0.5842 1.3335)
			(end 0.5842 -1.3335)
			(stroke
				(width 0)
				(type default)
			)
			(fill no)
			(layer "F.CrtYd")
		)
		(fp_rect
			(start -0.5842 1.3335)
			(end 0.5842 -1.3335)
			(stroke
				(width 0)
				(type default)
			)
			(fill no)
			(layer "F.Fab")
		)
		(pad "1" smd custom
			(at 0 -0.762 270)
			(size 0.2159 0.2159)
			(layers "F.Cu" "F.Mask" "F.Paste")
			(net "P12V_PCIE")
			(options
				(clearance outline)
				(anchor circle)
			)
			(primitives
				(gr_poly
					(pts
						(arc
							(start -0.3302 -0.4318)
							(mid -0.402042 -0.402042)
							(end -0.4318 -0.3302)
						)
						(arc
							(start -0.4318 0.3302)
							(mid -0.402042 0.402042)
							(end -0.3302 0.4318)
						)
						(arc
							(start 0.3302 0.4318)
							(mid 0.402042 0.402042)
							(end 0.4318 0.3302)
						)
						(arc
							(start 0.4318 -0.3302)
							(mid 0.402042 -0.402042)
							(end 0.3302 -0.4318)
						)
					)
					(width 0)
					(fill yes)
				)
			)
		)
		(pad "2" smd custom
			(at 0 0.762 270)
			(size 0.2159 0.2159)
			(layers "F.Cu" "F.Mask" "F.Paste")
			(net "MATED_P12V_EN")
			(options
				(clearance outline)
				(anchor circle)
			)
			(primitives
				(gr_poly
					(pts
						(arc
							(start -0.3302 -0.4318)
							(mid -0.402042 -0.402042)
							(end -0.4318 -0.3302)
						)
						(arc
							(start -0.4318 0.3302)
							(mid -0.402042 0.402042)
							(end -0.3302 0.4318)
						)
						(arc
							(start 0.3302 0.4318)
							(mid 0.402042 0.402042)
							(end 0.4318 0.3302)
						)
						(arc
							(start 0.4318 -0.3302)
							(mid 0.402042 -0.402042)
							(end 0.3302 -0.4318)
						)
					)
					(width 0)
					(fill yes)
				)
			)
		)
	)
	(footprint ""
		(layer "F.Cu")
		(at 120.4976 -17.0688)
		(property "Reference" "R746"
			(at 0 0 0)
			(layer "F.SilkS")
			(hide yes)
			(effects
				(font
					(size 1.27 1.27)
				)
			)
		)
		(property "Value" "4K7R2F-GP"
			(at 0.064008 -3.993896 0)
			(unlocked yes)
			(layer "F.Fab")
			(hide yes)
			(effects
				(font
					(size 1.016 1.016)
					(thickness 0.1524)
				)
			)
		)
		(property "Device Type" "R402H16"
			(at 0.064008 -5.517896 0)
			(unlocked yes)
			(layer "F.Fab")
			(hide yes)
			(effects
				(font
					(size 1.016 1.016)
					(thickness 0.1524)
				)
			)
		)
		(duplicate_pad_numbers_are_jumpers no)
		(fp_line
			(start -0.508 -0.9398)
			(end -0.508 0.9398)
			(stroke
				(width 0.1524)
				(type default)
			)
			(layer "F.SilkS")
		)
		(fp_line
			(start 0.508 -0.9398)
			(end -0.508 -0.9398)
			(stroke
				(width 0.1524)
				(type default)
			)
			(layer "F.SilkS")
		)
		(fp_rect
			(start -0.508 0.9398)
			(end 0.508 -0.9398)
			(stroke
				(width 0)
				(type default)
			)
			(fill no)
			(layer "F.CrtYd")
		)
		(fp_rect
			(start -0.508 0.9398)
			(end 0.508 -0.9398)
			(stroke
				(width 0)
				(type default)
			)
			(fill no)
			(layer "F.Fab")
		)
		(pad "1" smd custom
			(at 0 -0.4445)
			(size 0.1397 0.1397)
			(layers "F.Cu" "F.Mask" "F.Paste")
			(net "U54_A2")
			(options
				(clearance outline)
				(anchor circle)
			)
			(primitives
				(gr_poly
					(pts
						(arc
							(start -0.1778 -0.2794)
							(mid -0.249642 -0.249642)
							(end -0.2794 -0.1778)
						)
						(arc
							(start -0.2794 0.1778)
							(mid -0.249642 0.249642)
							(end -0.1778 0.2794)
						)
						(arc
							(start 0.1778 0.2794)
							(mid 0.249642 0.249642)
							(end 0.2794 0.1778)
						)
						(arc
							(start 0.2794 -0.1778)
							(mid 0.249642 -0.249642)
							(end 0.1778 -0.2794)
						)
					)
					(width 0)
					(fill yes)
				)
			)
		)
		(pad "2" smd custom
			(at 0 0.4445)
			(size 0.1397 0.1397)
			(layers "F.Cu" "F.Mask" "F.Paste")
			(net "P3V3_STBY")
			(options
				(clearance outline)
				(anchor circle)
			)
			(primitives
				(gr_poly
					(pts
						(arc
							(start -0.1778 -0.2794)
							(mid -0.249642 -0.249642)
							(end -0.2794 -0.1778)
						)
						(arc
							(start -0.2794 0.1778)
							(mid -0.249642 0.249642)
							(end -0.1778 0.2794)
						)
						(arc
							(start 0.1778 0.2794)
							(mid 0.249642 0.249642)
							(end 0.2794 0.1778)
						)
						(arc
							(start 0.2794 -0.1778)
							(mid 0.249642 -0.249642)
							(end 0.1778 -0.2794)
						)
					)
					(width 0)
					(fill yes)
				)
			)
		)
	)
	(footprint ""
		(layer "F.Cu")
		(at 53.730652 -112.25403 -90)
		(property "Reference" "R64"
			(at 0 0 270)
			(layer "F.SilkS")
			(hide yes)
			(effects
				(font
					(size 1.27 1.27)
				)
			)
		)
		(property "Value" "0R2J-2-GP"
			(at 0.064008 -3.993896 270)
			(unlocked yes)
			(layer "F.Fab")
			(hide yes)
			(effects
				(font
					(size 1.016 1.016)
					(thickness 0.1524)
				)
			)
		)
		(property "Device Type" "R402H16"
			(at 0.064008 -5.517896 270)
			(unlocked yes)
			(layer "F.Fab")
			(hide yes)
			(effects
				(font
					(size 1.016 1.016)
					(thickness 0.1524)
				)
			)
		)
		(duplicate_pad_numbers_are_jumpers no)
		(fp_line
			(start -0.508 -0.9398)
			(end -0.508 0.9398)
			(stroke
				(width 0.1524)
				(type default)
			)
			(layer "F.SilkS")
		)
		(fp_line
			(start 0.508 -0.9398)
			(end -0.508 -0.9398)
			(stroke
				(width 0.1524)
				(type default)
			)
			(layer "F.SilkS")
		)
		(fp_rect
			(start -0.508 0.9398)
			(end 0.508 -0.9398)
			(stroke
				(width 0)
				(type default)
			)
			(fill no)
			(layer "F.CrtYd")
		)
		(fp_rect
			(start -0.508 0.9398)
			(end 0.508 -0.9398)
			(stroke
				(width 0)
				(type default)
			)
			(fill no)
			(layer "F.Fab")
		)
		(pad "1" smd custom
			(at 0 -0.4445 270)
			(size 0.1397 0.1397)
			(layers "F.Cu" "F.Mask" "F.Paste")
			(net "BMC_I2C13_MINI7_SDA")
			(options
				(clearance outline)
				(anchor circle)
			)
			(primitives
				(gr_poly
					(pts
						(arc
							(start -0.1778 -0.2794)
							(mid -0.249642 -0.249642)
							(end -0.2794 -0.1778)
						)
						(arc
							(start -0.2794 0.1778)
							(mid -0.249642 0.249642)
							(end -0.1778 0.2794)
						)
						(arc
							(start 0.1778 0.2794)
							(mid 0.249642 0.249642)
							(end 0.2794 0.1778)
						)
						(arc
							(start 0.2794 -0.1778)
							(mid 0.249642 -0.249642)
							(end 0.1778 -0.2794)
						)
					)
					(width 0)
					(fill yes)
				)
			)
		)
		(pad "2" smd custom
			(at 0 0.4445 270)
			(size 0.1397 0.1397)
			(layers "F.Cu" "F.Mask" "F.Paste")
			(net "BMC_I2C13_MINI7_SDA_S")
			(options
				(clearance outline)
				(anchor circle)
			)
			(primitives
				(gr_poly
					(pts
						(arc
							(start -0.1778 -0.2794)
							(mid -0.249642 -0.249642)
							(end -0.2794 -0.1778)
						)
						(arc
							(start -0.2794 0.1778)
							(mid -0.249642 0.249642)
							(end -0.1778 0.2794)
						)
						(arc
							(start 0.1778 0.2794)
							(mid 0.249642 0.249642)
							(end 0.2794 0.1778)
						)
						(arc
							(start 0.2794 -0.1778)
							(mid 0.249642 -0.249642)
							(end 0.1778 -0.2794)
						)
					)
					(width 0)
					(fill yes)
				)
			)
		)
	)
	(footprint ""
		(layer "F.Cu")
		(at 49.40808 -212.420454 180)
		(property "Reference" "C365"
			(at 0 0 180)
			(layer "F.SilkS")
			(hide yes)
			(effects
				(font
					(size 1.27 1.27)
				)
			)
		)
		(property "Value" "SCD22U10V2KX-1GP"
			(at 1.1811 -2.7051 180)
			(unlocked yes)
			(layer "F.Fab")
			(hide yes)
			(effects
				(font
					(size 1.016 1.016)
					(thickness 0.1524)
				)
			)
		)
		(property "Device Type" "C402H22"
			(at 1.1811 -4.2291 180)
			(unlocked yes)
			(layer "F.Fab")
			(hide yes)
			(effects
				(font
					(size 1.016 1.016)
					(thickness 0.1524)
				)
			)
		)
		(duplicate_pad_numbers_are_jumpers no)
		(fp_rect
			(start -0.4318 0.9525)
			(end 0.4318 -0.9525)
			(stroke
				(width 0)
				(type default)
			)
			(fill no)
			(layer "F.CrtYd")
		)
		(fp_rect
			(start -0.4318 0.9525)
			(end 0.4318 -0.9525)
			(stroke
				(width 0)
				(type default)
			)
			(fill no)
			(layer "F.Fab")
		)
		(pad "1" smd custom
			(at 0 -0.4445 180)
			(size 0.1524 0.1524)
			(layers "F.Cu" "F.Mask" "F.Paste")
			(net "PCIE_TX_CAP_N75")
			(options
				(clearance outline)
				(anchor circle)
			)
			(primitives
				(gr_poly
					(pts
						(arc
							(start 0.3048 -0.2032)
							(mid 0.275042 -0.275042)
							(end 0.2032 -0.3048)
						)
						(arc
							(start -0.2032 -0.3048)
							(mid -0.275042 -0.275042)
							(end -0.3048 -0.2032)
						)
						(arc
							(start -0.3048 0.2032)
							(mid -0.275042 0.275042)
							(end -0.2032 0.3048)
						)
						(arc
							(start 0.2032 0.3048)
							(mid 0.275042 0.275042)
							(end 0.3048 0.2032)
						)
					)
					(width 0)
					(fill yes)
				)
			)
		)
		(pad "2" smd custom
			(at 0 0.4445 180)
			(size 0.1524 0.1524)
			(layers "F.Cu" "F.Mask" "F.Paste")
			(net "PCIE_TX_N75")
			(options
				(clearance outline)
				(anchor circle)
			)
			(primitives
				(gr_poly
					(pts
						(arc
							(start 0.3048 -0.2032)
							(mid 0.275042 -0.275042)
							(end 0.2032 -0.3048)
						)
						(arc
							(start -0.2032 -0.3048)
							(mid -0.275042 -0.275042)
							(end -0.3048 -0.2032)
						)
						(arc
							(start -0.3048 0.2032)
							(mid -0.275042 0.275042)
							(end -0.2032 0.3048)
						)
						(arc
							(start 0.2032 0.3048)
							(mid 0.275042 0.275042)
							(end 0.3048 0.2032)
						)
					)
					(width 0)
					(fill yes)
				)
			)
		)
	)
)
